# S9S_MB_2U (Grand Teton) — schematic parts with pin connectivity, parts 5876–5876 of 6093; source: Cadence DE-HDL packaged netlist (pstxprt.dat, pstxnet.dat, pstchip.dat)

U1  SOCKET4677_AZIF0045P001C01CS  SOCKET4677_AZIF0045-P001C01CS IO  pkg SOCKET4677_82X64-5XA_H466  page 44  (pins 2617-2943 of 4677)
  DF4  VSS1017  POWER  = GND
  DF6  UPI1_TX_DP10  OUT  = UPI_CPU1_CPU0_P1P0_DP<10>
  DF8  VSS1019  POWER  = GND
  DF10  PE2_RX_DP4  IN  = P5E_CPU1_PE2_RX_DP<4>
  DF12  VSS798  POWER  = GND
  DF14  PE2_TX_DN5  OUT  = P5E_CPU1_PE2_TX_DN<5>
  DF16  VSS799  POWER  = GND
  DF18  DDR7_SB_DQS_DN8  BI  = M_H_CPU1_SB_DQS_DN<8>
  DF20  DDR7_SB_DQ26  BI  = M_H_CPU1_SB_DQ<26>
  DF22  DDR7_SB_DQ15  BI  = M_H_CPU1_SB_DQ<15>
  DF24  DDR7_SB_DQS_DP6  BI  = M_H_CPU1_SB_DQS_DP<6>
  DF26  DDR7_SB_DQ10  BI  = M_H_CPU1_SB_DQ<10>
  DF28  DDR7_SB_DQ5  BI  = M_H_CPU1_SB_DQ<5>
  DF30  DDR7_SB_DQS_DP5  BI  = M_H_CPU1_SB_DQS_DP<5>
  DF32  DDR7_SB_DQ2  BI  = M_H_CPU1_SB_DQ<2>
  DF34  DDR7_SB_ECC3  BI  = M_H_CPU1_SB_CB<3>
  DF36  DDR7_SB_DQS_DP4  BI  = M_H_CPU1_SB_DQS_DP<4>
  DF38  DDR7_SB_ECC4  BI  = M_H_CPU1_SB_CB<4>
  DF40  DDR7_SB_CA0  OUT  = M_H_CPU1_SB_CA<0>
  DF42  DDR7_CLK_DP0  OUT  = M_H_CPU1_CLK_DP<0>
  DF44  DDR4_B_RSP0  IN  = M_E_CPU1_SB_RSP<0>
  DF47  DDR7_SA_CA5  OUT  = M_H_CPU1_SA_CA<5>
  DF49  VSS802  POWER  = GND
  DF51  DDR7_SA_CS_N0  OUT  = M_H_CPU1_SA_CS_N<0>
  DF53  DDR7_SA_ECC7  BI  = M_H_CPU1_SA_CB<7>
  DF55  DDR7_SA_DQS_DP9  BI  = M_H_CPU1_SA_DQS_DP<9>
  DF57  DDR7_SA_ECC2  BI  = M_H_CPU1_SA_CB<2>
  DF59  DDR7_SA_DQ31  BI  = M_H_CPU1_SA_DQ<31>
  DF61  DDR7_SA_DQS_DP8  BI  = M_H_CPU1_SA_DQS_DP<8>
  DF63  DDR7_SA_DQ26  BI  = M_H_CPU1_SA_DQ<26>
  DF65  DDR7_SA_DQ23  BI  = M_H_CPU1_SA_DQ<23>
  DF67  DDR7_SA_DQS_DP7  BI  = M_H_CPU1_SA_DQS_DP<7>
  DF69  DDR7_SA_DQ18  BI  = M_H_CPU1_SA_DQ<18>
  DF71  DDR7_SA_DQ15  BI  = M_H_CPU1_SA_DQ<15>
  DF73  DDR7_SA_DQS_DP6  BI  = M_H_CPU1_SA_DQS_DP<6>
  DF75  DDR7_SA_DQ10  BI  = M_H_CPU1_SA_DQ<10>
  DF77  UPI3_RX_DN16  IN  = GND
  DF79  VSS1018  POWER  = GND
  DF81  UPI3_RX_DP13  IN  = GND
  DF83  UPI3_RX_DN12  IN  = GND
  DF85  PE3_TX_DN9  OUT  = P5E_CPU1_PE3_TX_DN<9>
  DF87  VSS1020  POWER  = GND
  DF89  PE3_RX_DP10  IN  = P5E_CPU1_PE3_RX_DP<10>
  DF91  VSS806  POWER  = GND
  DG1  VSS807  POWER  = GND
  DG3  UPI1_RX_DN10  IN  = UPI_CPU0_CPU1_P0P1_DN<10>
  DG5  VSS1031  POWER  = GND
  DG7  UPI1_TX_DP9  OUT  = UPI_CPU1_CPU0_P1P0_DP<9>
  DG9  VSS1038  POWER  = GND
  DG11  PE2_RX_DP5  IN  = P5E_CPU1_PE2_RX_DP<5>
  DG13  VSS808  POWER  = GND
  DG15  PE2_TX_DP5  OUT  = P5E_CPU1_PE2_TX_DP<5>
  DG17  DDR7_SB_DQ28  BI  = M_H_CPU1_SB_DQ<28>
  DG19  DDR7_SB_DQ27  BI  = M_H_CPU1_SB_DQ<27>
  DG21  VSS809  POWER  = GND
  DG23  DDR7_SB_DQ14  BI  = M_H_CPU1_SB_DQ<14>
  DG25  DDR7_SB_DQ11  BI  = M_H_CPU1_SB_DQ<11>
  DG27  VSS1022  POWER  = GND
  DG29  DDR7_SB_DQ6  BI  = M_H_CPU1_SB_DQ<6>
  DG31  DDR7_SB_DQ3  BI  = M_H_CPU1_SB_DQ<3>
  DG33  VSS1024  POWER  = GND
  DG35  DDR7_SB_ECC2  BI  = M_H_CPU1_SB_CB<2>
  DG37  DDR7_SB_ECC5  BI  = M_H_CPU1_SB_CB<5>
  DG39  VSS1027  POWER  = GND
  DG41  DDR7_SB_CA1  OUT  = M_H_CPU1_SB_CA<1>
  DG43  DDR4_B_RSP1  IN  = M_E_CPU1_SB_RSP<1>
  DG45  VSS1030  POWER  = GND
  DG48  DDR7_SA_CA3  OUT  = M_H_CPU1_SA_CA<3>
  DG50  DDR7_SA_CS_N1  OUT  = M_H_CPU1_SA_CS_N<1>
  DG52  VSS817  POWER  = GND
  DG54  DDR7_SA_ECC6  BI  = M_H_CPU1_SA_CB<6>
  DG56  DDR7_SA_ECC3  BI  = M_H_CPU1_SA_CB<3>
  DG58  VSS820  POWER  = GND
  DG60  DDR7_SA_DQ30  BI  = M_H_CPU1_SA_DQ<30>
  DG62  DDR7_SA_DQ27  BI  = M_H_CPU1_SA_DQ<27>
  DG64  VSS821  POWER  = GND
  DG66  DDR7_SA_DQ22  BI  = M_H_CPU1_SA_DQ<22>
  DG68  DDR7_SA_DQ19  BI  = M_H_CPU1_SA_DQ<19>
  DG70  VSS1032  POWER  = GND
  DG72  DDR7_SA_DQ14  BI  = M_H_CPU1_SA_DQ<14>
  DG74  DDR7_SA_DQ11  BI  = M_H_CPU1_SA_DQ<11>
  DG76  VSS1033  POWER  = GND
  DG78  UPI3_RX_DN10  IN  = GND
  DG80  VSS1034  POWER  = GND
  DG82  UPI3_RX_DP11  IN  = GND
  DG84  VSS1035  POWER  = GND
  DG86  PE3_TX_DP9  OUT  = P5E_CPU1_PE3_TX_DP<9>
  DG88  VSS1037  POWER  = GND
  DG90  PE3_RX_DN10  IN  = P5E_CPU1_PE3_RX_DN<10>
  DH2  UPI1_RX_DP10  IN  = UPI_CPU0_CPU1_P0P1_DP<10>
  DH4  VSS1044  POWER  = GND
  DH6  UPI1_TX_DN9  OUT  = UPI_CPU1_CPU0_P1P0_DN<9>
  DH8  VSS1057  POWER  = GND
  DH10  PE2_RX_DN5  IN  = P5E_CPU1_PE2_RX_DN<5>
  DH12  VSS1039  POWER  = GND
  DH14  PE2_TX_DP6  OUT  = P5E_CPU1_PE2_TX_DP<6>
  DH16  VSS829  POWER  = GND
  DH18  DDR7_SB_DQS_DP8  BI  = M_H_CPU1_SB_DQS_DP<8>
  DH20  VSS830  POWER  = GND
  DH22  VSS1040  POWER  = GND
  DH24  DDR7_SB_DQS_DN6  BI  = M_H_CPU1_SB_DQS_DN<6>
  DH26  VSS832  POWER  = GND
  DH28  VSS1041  POWER  = GND
  DH30  DDR7_SB_DQS_DN5  BI  = M_H_CPU1_SB_DQS_DN<5>
  DH32  VSS1042  POWER  = GND
  DH34  VSS835  POWER  = GND
  DH36  DDR7_SB_DQS_DN4  BI  = M_H_CPU1_SB_DQS_DN<4>
  DH38  VSS1043  POWER  = GND
  DH40  VSS1045  POWER  = GND
  DH42  DDR7_CLK_DN0  OUT  = M_H_CPU1_CLK_DN<0>
  DH44  VSS839  POWER  = GND
  DH47  VSS1046  POWER  = GND
  DH49  DDR7_SA_CA1  OUT  = M_H_CPU1_SA_CA<1>
  DH51  VSS841  POWER  = GND
  DH53  VSS842  POWER  = GND
  DH55  DDR7_SA_DQS_DN9  BI  = M_H_CPU1_SA_DQS_DN<9>
  DH57  VSS1049  POWER  = GND
  DH59  VSS844  POWER  = GND
  DH61  DDR7_SA_DQS_DN8  BI  = M_H_CPU1_SA_DQS_DN<8>
  DH63  VSS845  POWER  = GND
  DH65  VSS1053  POWER  = GND
  DH67  DDR7_SA_DQS_DN7  BI  = M_H_CPU1_SA_DQS_DN<7>
  DH69  VSS847  POWER  = GND
  DH71  VSS1055  POWER  = GND
  DH73  DDR7_SA_DQS_DN6  BI  = M_H_CPU1_SA_DQS_DN<6>
  DH75  VSS849  POWER  = GND
  DH77  VSS1056  POWER  = GND
  DH79  UPI3_RX_DP10  IN  = GND
  DH81  UPI3_RX_DN11  IN  = GND
  DH83  UPI3_RX_DP12  IN  = GND
  DH85  VSS1058  POWER  = GND
  DH87  PE3_TX_DN8  OUT  = P5E_CPU1_PE3_TX_DN<8>
  DH89  VCCFA_EHV_FIVRA50  POWER  = PVCCFA_EHV_FIVRA_CPU1
  DH91  PE3_RX_DN9  IN  = P5E_CPU1_PE3_RX_DN<9>
  DJ1  UPI1_RX_DN9  IN  = UPI_CPU0_CPU1_P0P1_DN<9>
  DJ3  VCCINFAON31  POWER  = PVCCINFAON_CPU1
  DJ5  UPI1_TX_DP8  OUT  = UPI_CPU1_CPU0_P1P0_DP<8>
  DJ7  VCCINFAON32  POWER  = PVCCINFAON_CPU1
  DJ9  PE2_RX_DN6  IN  = P5E_CPU1_PE2_RX_DN<6>
  DJ11  VCCINFAON59  POWER  = PVCCINFAON_CPU1
  DJ13  PE2_TX_DN6  OUT  = P5E_CPU1_PE2_TX_DN<6>
  DJ15  VCCINFAON30  POWER  = PVCCINFAON_CPU1
  DJ17  DDR7_SB_DQ30  BI  = M_H_CPU1_SB_DQ<30>
  DJ19  VSS1061  POWER  = GND
  DJ21  DDR7_SB_DQS_DP2  BI  = M_H_CPU1_SB_DQS_DP<2>
  DJ23  VSS1062  POWER  = GND
  DJ25  VSS857  POWER  = GND
  DJ27  DDR6_SB_DQS_DN1  BI  = M_G_CPU1_SB_DQS_DN<1>
  DJ29  VSS1065  POWER  = GND
  DJ31  VSS1066  POWER  = GND
  DJ33  DDR6_SB_DQS_DN0  BI  = M_G_CPU1_SB_DQS_DN<0>
  DJ35  VSS861  POWER  = GND
  DJ37  VSS1067  POWER  = GND
  DJ39  DDR7_SB_CA6  OUT  = M_H_CPU1_SB_CA<6>
  DJ41  VSS1068  POWER  = GND
  DJ43  VSS1069  POWER  = GND
  DJ45  DDR6_CLK_DP1  OUT  = M_G_CPU1_CLK_DP<1>
  DJ48  VSS1070  POWER  = GND
  DJ50  VSS1071  POWER  = GND
  DJ52  DDR6_SA_CA0  OUT  = M_G_CPU1_SA_CA<0>
  DJ54  VSS867  POWER  = GND
  DJ56  VSS1072  POWER  = GND
  DJ58  DDR6_SA_DQS_DP4  BI  = M_G_CPU1_SA_DQS_DP<4>
  DJ60  VSS1073  POWER  = GND
  DJ62  VSS870  POWER  = GND
  DJ64  DDR6_SA_DQS_DP3  BI  = M_G_CPU1_SA_DQS_DP<3>
  DJ66  VSS1074  POWER  = GND
  DJ68  VSS872  POWER  = GND
  DJ70  DDR6_SA_DQS_DN1  BI  = M_G_CPU1_SA_DQS_DN<1>
  DJ72  VSS1075  POWER  = GND
  DJ74  VSS1076  POWER  = GND
  DJ76  DDR7_SA_DQS_DN0  BI  = M_H_CPU1_SA_DQS_DN<0>
  DJ78  UPI3_RX_DN9  IN  = GND
  DJ80  VSS1078  POWER  = GND
  DJ82  VSS1079  POWER  = GND
  DJ84  VSS1080  POWER  = GND
  DJ86  PE3_TX_DP8  OUT  = P5E_CPU1_PE3_TX_DP<8>
  DJ88  VSS1081  POWER  = GND
  DJ90  PE3_RX_DP9  IN  = P5E_CPU1_PE3_RX_DP<9>
  DK2  UPI1_RX_DP9  IN  = UPI_CPU0_CPU1_P0P1_DP<9>
  DK4  VSS1085  POWER  = GND
  DK6  UPI1_TX_DN8  OUT  = UPI_CPU1_CPU0_P1P0_DN<8>
  DK8  VSS1090  POWER  = GND
  DK10  PE2_RX_DP6  IN  = P5E_CPU1_PE2_RX_DP<6>
  DK12  VSS880  POWER  = GND
  DK14  PE2_TX_DN7  OUT  = P5E_CPU1_PE2_TX_DN<7>
  DK16  VSS1082  POWER  = GND
  DK18  VSS882  POWER  = GND
  DK20  DDR7_SB_DQ20  BI  = M_H_CPU1_SB_DQ<20>
  DK22  DDR7_SB_DQ17  BI  = M_H_CPU1_SB_DQ<17>
  DK24  VSS883  POWER  = GND
  DK26  DDR6_SB_DQ12  BI  = M_G_CPU1_SB_DQ<12>
  DK28  DDR6_SB_DQ9  BI  = M_G_CPU1_SB_DQ<9>
  DK30  VSS1083  POWER  = GND
  DK32  DDR6_SB_DQ4  BI  = M_G_CPU1_SB_DQ<4>
  DK34  DDR6_SB_DQ1  BI  = M_G_CPU1_SB_DQ<1>
  DK36  VSS1084  POWER  = GND
  DK38  DDR7_SB_CS_N2  OUT  = M_H_CPU1_SB_CS_N<2>
  DK40  DDR7_SB_CA4  OUT  = M_H_CPU1_SB_CA<4>
  DK42  VSS887  POWER  = GND
  DK44  DDR6_SA_CA6  OUT  = M_G_CPU1_SA_CA<6>
  DK47  DDR5_B_RSP1  IN  = M_F_CPU1_SB_RSP<1>
  DK49  VSS1086  POWER  = GND
  DK51  DDR6_SA_CA2  OUT  = M_G_CPU1_SA_CA<2>
  DK53  DDR6_SA_CS_N3  OUT  = M_G_CPU1_SA_CS_N<3>
  DK55  VSS890  POWER  = GND
  DK57  DDR6_SA_ECC4  BI  = M_G_CPU1_SA_CB<4>
  DK59  DDR6_SA_ECC1  BI  = M_G_CPU1_SA_CB<1>
  DK61  VSS893  POWER  = GND
  DK63  DDR6_SA_DQ28  BI  = M_G_CPU1_SA_DQ<28>
  DK65  DDR6_SA_DQ25  BI  = M_G_CPU1_SA_DQ<25>
  DK67  VSS894  POWER  = GND
  DK69  DDR6_SA_DQ12  BI  = M_G_CPU1_SA_DQ<12>
  DK71  DDR6_SA_DQ9  BI  = M_G_CPU1_SA_DQ<9>
  DK73  VSS1087  POWER  = GND
  DK75  DDR7_SA_DQ4  BI  = M_H_CPU1_SA_DQ<4>
  DK77  VSS1088  POWER  = GND
  DK79  VSS1089  POWER  = GND
  DK81  VSS1091  POWER  = GND
  DK83  VSS1092  POWER  = GND
  DK85  PE3_TX_DN7  OUT  = P5E_CPU1_PE3_TX_DN<7>
  DK87  VSS1093  POWER  = GND
  DK89  PE3_RX_DP8  IN  = P5E_CPU1_PE3_RX_DP<8>
  DK91  VSS1094  POWER  = GND
  DL1  VSS903  POWER  = GND
  DL3  UPI1_RX_DN8  IN  = UPI_CPU0_CPU1_P0P1_DN<8>
  DL5  VSS908  POWER  = GND
  DL7  UPI1_TX_DN7  OUT  = UPI_CPU1_CPU0_P1P0_DN<7>
  DL9  VSS1099  POWER  = GND
  DL11  PE2_RX_DP7  IN  = P5E_CPU1_PE2_RX_DP<7>
  DL13  VSS904  POWER  = GND
  DL15  PE2_TX_DP7  OUT  = P5E_CPU1_PE2_TX_DP<7>
  DL17  VSS905  POWER  = GND
  DL19  DDR7_SB_DQ21  BI  = M_H_CPU1_SB_DQ<21>
  DL21  DDR7_SB_DQS_DN2  BI  = M_H_CPU1_SB_DQS_DN<2>
  DL23  DDR7_SB_DQ16  BI  = M_H_CPU1_SB_DQ<16>
  DL25  DDR6_SB_DQ13  BI  = M_G_CPU1_SB_DQ<13>
  DL27  DDR6_SB_DQS_DP1  BI  = M_G_CPU1_SB_DQS_DP<1>
  DL29  DDR6_SB_DQ10  BI  = M_G_CPU1_SB_DQ<10>
  DL31  DDR6_SB_DQ5  BI  = M_G_CPU1_SB_DQ<5>
  DL33  DDR6_SB_DQS_DP0  BI  = M_G_CPU1_SB_DQS_DP<0>
  DL35  DDR6_SB_DQ0  BI  = M_G_CPU1_SB_DQ<0>
  DL37  DDR7_SB_CS_N0  OUT  = M_H_CPU1_SB_CS_N<0>
  DL39  VSS1095  POWER  = GND
  DL41  DDR7_SB_CA2  OUT  = M_H_CPU1_SB_CA<2>
  DL43  DDR6_SA_PAR  OUT  = M_G_CPU1_SA_PAR
  DL45  DDR6_CLK_DN1  OUT  = M_G_CPU1_CLK_DN<1>
  DL48  DDR5_B_RSP0  IN  = M_F_CPU1_SB_RSP<0>
  DL50  DDR6_SA_CA4  OUT  = M_G_CPU1_SA_CA<4>
  DL52  VSS909  POWER  = GND
  DL54  DDR6_SA_CS_N2  OUT  = M_G_CPU1_SA_CS_N<2>
  DL56  DDR6_SA_ECC5  BI  = M_G_CPU1_SA_CB<5>
  DL58  DDR6_SA_DQS_DN4  BI  = M_G_CPU1_SA_DQS_DN<4>
  DL60  DDR6_SA_ECC0  BI  = M_G_CPU1_SA_CB<0>
  DL62  DDR6_SA_DQ29  BI  = M_G_CPU1_SA_DQ<29>
  DL64  DDR6_SA_DQS_DN3  BI  = M_G_CPU1_SA_DQS_DN<3>
  DL66  DDR6_SA_DQ24  BI  = M_G_CPU1_SA_DQ<24>
  DL68  DDR6_SA_DQ13  BI  = M_G_CPU1_SA_DQ<13>
  DL70  DDR6_SA_DQS_DP1  BI  = M_G_CPU1_SA_DQS_DP<1>
  DL72  DDR6_SA_DQ8  BI  = M_G_CPU1_SA_DQ<8>
  DL74  DDR7_SA_DQ5  BI  = M_H_CPU1_SA_DQ<5>
  DL76  DDR7_SA_DQS_DP0  BI  = M_H_CPU1_SA_DQS_DP<0>
  DL78  UPI3_RX_DP9  IN  = GND
  DL80  UPI3_TX_DN11  OUT  = NC
  DL82  UPI3_TX_DP10  OUT  = NC
  DL84  VSS1096  POWER  = GND
  DL86  PE3_TX_DP7  OUT  = P5E_CPU1_PE3_TX_DP<7>
  DL88  VSS1098  POWER  = GND
  DL90  PE3_RX_DN8  IN  = P5E_CPU1_PE3_RX_DN<8>
  DM2  UPI1_RX_DP8  IN  = UPI_CPU0_CPU1_P0P1_DP<8>
  DM4  VSS1117  POWER  = GND
  DM6  UPI1_TX_DP7  OUT  = UPI_CPU1_CPU0_P1P0_DP<7>
  DM8  VSS1140  POWER  = GND
  DM10  PE2_RX_DN7  IN  = P5E_CPU1_PE2_RX_DN<7>
  DM12  VSS1100  POWER  = GND
  DM14  PE2_TX_DP8  OUT  = P5E_CPU1_PE2_TX_DP<8>
  DM16  VSS1101  POWER  = GND
  DM18  VSS1102  POWER  = GND
  DM20  VSS1103  POWER  = GND
  DM22  VSS1104  POWER  = GND
  DM24  VSS1105  POWER  = GND
  DM26  VSS1106  POWER  = GND
  DM28  VSS1107  POWER  = GND
  DM30  VSS1108  POWER  = GND
  DM32  VSS1109  POWER  = GND
  DM34  VSS1110  POWER  = GND
  DM36  VSS1113  POWER  = GND
  DM38  VSS1114  POWER  = GND
  DM40  VSS1118  POWER  = GND
  DM42  VSS1119  POWER  = GND
  DM44  VSS1120  POWER  = GND
  DM47  VSS1121  POWER  = GND
  DM49  VSS1122  POWER  = GND
  DM51  VSS934  POWER  = GND
  DM53  VSS1123  POWER  = GND
  DM55  VSS1124  POWER  = GND
  DM57  VSS1127  POWER  = GND
  DM59  VSS1128  POWER  = GND
  DM61  VSS1130  POWER  = GND
  DM63  VSS1132  POWER  = GND
  DM65  VSS1133  POWER  = GND
  DM67  VSS1134  POWER  = GND
  DM69  VSS1135  POWER  = GND
  DM71  VSS1136  POWER  = GND
  DM73  VSS945  POWER  = GND
  DM75  VSS1137  POWER  = GND
  DM77  VSS1138  POWER  = GND
  DM79  VSS1139  POWER  = GND
  DM81  UPI3_TX_DN10  OUT  = NC
  DM83  VCCFA_EHV_FIVRA51  POWER  = PVCCFA_EHV_FIVRA_CPU1
  DM85  VCCFA_EHV_FIVRA52  POWER  = PVCCFA_EHV_FIVRA_CPU1
  DM87  PE3_TX_DN6  OUT  = P5E_CPU1_PE3_TX_DN<6>
  DM89  VCCFA_EHV_FIVRA53  POWER  = PVCCFA_EHV_FIVRA_CPU1
  DM91  PE3_RX_DP7  IN  = P5E_CPU1_PE3_RX_DP<7>
  DN1  UPI1_RX_DN7  IN  = UPI_CPU0_CPU1_P0P1_DN<7>
  DN3  VCCFA_EHV_FIVRA56  POWER  = PVCCFA_EHV_FIVRA_CPU1
  DN5  UPI1_TX_DP6  OUT  = UPI_CPU1_CPU0_P1P0_DP<6>
  DN7  VCCFA_EHV_FIVRA57  POWER  = PVCCFA_EHV_FIVRA_CPU1
  DN9  PE2_RX_DN8  IN  = P5E_CPU1_PE2_RX_DN<8>
  DN11  VCCFA_EHV_FIVRA54  POWER  = PVCCFA_EHV_FIVRA_CPU1
  DN13  PE2_TX_DN8  OUT  = P5E_CPU1_PE2_TX_DN<8>
  DN15  VCCFA_EHV_FIVRA55  POWER  = PVCCFA_EHV_FIVRA_CPU1
  DN17  VSS955  POWER  = GND
  DN19  DDR7_SB_DQ23  BI  = M_H_CPU1_SB_DQ<23>
  DN21  DDR7_SB_DQS_DP7  BI  = M_H_CPU1_SB_DQS_DP<7>
  DN23  DDR7_SB_DQ18  BI  = M_H_CPU1_SB_DQ<18>
  DN25  DDR6_SB_DQ15  BI  = M_G_CPU1_SB_DQ<15>
